(kicad_pcb
	(version 20260206)
	(generator "pcbnew")
	(generator_version "10.0")
	(general
		(thickness 1.6)
		(legacy_teardrops no)
	)
	(paper "A4")
	(title_block
		(title "04192023_DAF0TMB3IC0_F0TG_MB_C_brd_V02_OCP.brd")
		(comment 1 "Grand Teton / footprint 2783 of 8354 (U26), pads 1086-1199 of 6102")
	)
	(layers
		(0 "F.Cu" signal "TOP")
		(4 "In1.Cu" signal "GND")
		(6 "In2.Cu" signal "IN1")
		(8 "In3.Cu" signal "GND1")
		(10 "In4.Cu" signal "IN2")
		(12 "In5.Cu" signal "GND2")
		(14 "In6.Cu" signal "IN3")
		(16 "In7.Cu" signal "GND3")
		(18 "In8.Cu" signal "VCC")
		(20 "In9.Cu" signal "VCC1")
		(22 "In10.Cu" signal "GND4")
		(24 "In11.Cu" signal "IN4")
		(26 "In12.Cu" signal "GND5")
		(28 "In13.Cu" signal "IN5")
		(30 "In14.Cu" signal "GND6")
		(32 "In15.Cu" signal "IN6")
		(34 "In16.Cu" signal "GND7")
		(2 "B.Cu" signal "BOTTOM")
		(9 "F.Adhes" user "F.Adhesive")
		(11 "B.Adhes" user "B.Adhesive")
		(13 "F.Paste" user "Package Geometry/Pastemask Top")
		(15 "B.Paste" user "Package Geometry/Pastemask Bottom")
		(5 "F.SilkS" user "Ref Des/Silkscreen Top")
		(7 "B.SilkS" user "Ref Des/Silkscreen Bottom")
		(1 "F.Mask" user "Board Geometry/Soldermask Top")
		(3 "B.Mask" user "Board Geometry/Soldermask Bottom")
		(17 "Dwgs.User" user "User.Drawings")
		(19 "Cmts.User" user "User.Comments")
		(21 "Eco1.User" user "User.Eco1")
		(23 "Eco2.User" user "User.Eco2")
		(25 "Edge.Cuts" user "Board Geometry/Outline")
		(27 "Margin" user)
		(31 "F.CrtYd" user "Package Geometry/Place Bound Top")
		(29 "B.CrtYd" user "Package Geometry/Place Bound Bottom")
		(35 "F.Fab" user "Ref Des/Assembly Top")
		(33 "B.Fab" user "Ref Des/Assembly Bottom")
	)
	(footprint ""
		(layer "F.Cu")
		(at 111.927894 -258.880356 180)
		(property "Reference" "U26"
			(at -45.05579 -61.794136 0)
			(unlocked yes)
			(layer "F.SilkS")
			(effects
				(font
					(size 0.7874 0.5842)
					(thickness 0.1524)
				)
			)
		)
		(property "Value" ""
			(at 0 0 180)
			(layer "F.Fab")
			(effects
				(font
					(size 1.27 1.27)
				)
			)
		)
		(duplicate_pad_numbers_are_jumpers no)
		(pad "AR16" smd circle
			(at -20.059904 -9.269984 180)
			(size 0.450088 0.450088)
			(layers "F.Cu" "F.Mask" "F.Paste")
			(net "GND")
		)
		(pad "AR17" smd circle
			(at -19.120104 -9.269984 180)
			(size 0.450088 0.450088)
			(layers "F.Cu" "F.Mask" "F.Paste")
			(net "M_J_CPU1_SA_CB<7>")
		)
		(pad "AR18" smd circle
			(at -18.18005 -9.269984 180)
			(size 0.450088 0.450088)
			(layers "F.Cu" "F.Mask" "F.Paste")
			(net "PVDDCR_SOC_P1")
		)
		(pad "AR19" smd circle
			(at -17.239996 -9.269984 180)
			(size 0.450088 0.450088)
			(layers "F.Cu" "F.Mask" "F.Paste")
			(net "GND")
		)
		(pad "AR20" smd circle
			(at -16.299942 -9.269984 180)
			(size 0.450088 0.450088)
			(layers "F.Cu" "F.Mask" "F.Paste")
			(net "GND")
		)
		(pad "AR21" smd circle
			(at -15.359888 -9.269984 180)
			(size 0.450088 0.450088)
			(layers "F.Cu" "F.Mask" "F.Paste")
			(net "M_I_CPU1_SA_CB<7>")
		)
		(pad "AR22" smd circle
			(at -14.420088 -9.269984 180)
			(size 0.450088 0.450088)
			(layers "F.Cu" "F.Mask" "F.Paste")
			(net "GND")
		)
		(pad "AR23" smd circle
			(at -13.480034 -9.269984 180)
			(size 0.450088 0.450088)
			(layers "F.Cu" "F.Mask" "F.Paste")
			(net "PVDDCR_CPU0_P1")
		)
		(pad "AR24" smd circle
			(at -12.53998 -9.269984 180)
			(size 0.450088 0.450088)
			(layers "F.Cu" "F.Mask" "F.Paste")
			(net "GND")
		)
		(pad "AR25" smd circle
			(at -11.599926 -9.269984 180)
			(size 0.450088 0.450088)
			(layers "F.Cu" "F.Mask" "F.Paste")
			(net "PVDDCR_CPU0_P1")
		)
		(pad "AR26" smd circle
			(at -10.659872 -9.269984 180)
			(size 0.450088 0.450088)
			(layers "F.Cu" "F.Mask" "F.Paste")
			(net "GND")
		)
		(pad "AR27" smd circle
			(at -9.720072 -9.269984 180)
			(size 0.450088 0.450088)
			(layers "F.Cu" "F.Mask" "F.Paste")
			(net "PVDDCR_CPU0_P1")
		)
		(pad "AR28" smd circle
			(at -8.780018 -9.269984 180)
			(size 0.450088 0.450088)
			(layers "F.Cu" "F.Mask" "F.Paste")
			(net "GND")
		)
		(pad "AR29" smd circle
			(at -7.839964 -9.269984 180)
			(size 0.450088 0.450088)
			(layers "F.Cu" "F.Mask" "F.Paste")
			(net "PVDDCR_CPU0_P1")
		)
		(pad "AR30" smd circle
			(at -6.89991 -9.269984 180)
			(size 0.450088 0.450088)
			(layers "F.Cu" "F.Mask" "F.Paste")
			(net "GND")
		)
		(pad "AR31" smd circle
			(at -5.96011 -9.269984 180)
			(size 0.450088 0.450088)
			(layers "F.Cu" "F.Mask" "F.Paste")
			(net "PVDDCR_CPU0_P1")
		)
		(pad "AR32" smd circle
			(at -5.020056 -9.269984 180)
			(size 0.450088 0.450088)
			(layers "F.Cu" "F.Mask" "F.Paste")
			(net "GND")
		)
		(pad "AR33" smd circle
			(at -4.080002 -9.269984 180)
			(size 0.450088 0.450088)
			(layers "F.Cu" "F.Mask" "F.Paste")
			(net "PVDDCR_CPU0_P1")
		)
		(pad "AR34" smd circle
			(at -3.139948 -9.269984 180)
			(size 0.450088 0.450088)
			(layers "F.Cu" "F.Mask" "F.Paste")
			(net "GND")
		)
		(pad "AR35" smd circle
			(at -2.199894 -9.269984 180)
			(size 0.450088 0.450088)
			(layers "F.Cu" "F.Mask" "F.Paste")
			(net "PVDDCR_CPU0_P1")
		)
		(pad "AR36" smd circle
			(at -1.260094 -9.269984 180)
			(size 0.450088 0.450088)
			(layers "F.Cu" "F.Mask" "F.Paste")
			(net "GND")
		)
		(pad "AR40" smd circle
			(at 1.560068 -9.269984 180)
			(size 0.450088 0.450088)
			(layers "F.Cu" "F.Mask" "F.Paste")
			(net "PVDDCR_CPU0_P1")
		)
		(pad "AR41" smd circle
			(at 2.500122 -9.269984 180)
			(size 0.450088 0.450088)
			(layers "F.Cu" "F.Mask" "F.Paste")
			(net "GND")
		)
		(pad "AR42" smd circle
			(at 3.439922 -9.269984 180)
			(size 0.450088 0.450088)
			(layers "F.Cu" "F.Mask" "F.Paste")
			(net "PVDDCR_CPU0_P1")
		)
		(pad "AR43" smd circle
			(at 4.379976 -9.269984 180)
			(size 0.450088 0.450088)
			(layers "F.Cu" "F.Mask" "F.Paste")
			(net "GND")
		)
		(pad "AR44" smd circle
			(at 5.32003 -9.269984 180)
			(size 0.450088 0.450088)
			(layers "F.Cu" "F.Mask" "F.Paste")
			(net "PVDDCR_CPU0_P1")
		)
		(pad "AR45" smd circle
			(at 6.260084 -9.269984 180)
			(size 0.450088 0.450088)
			(layers "F.Cu" "F.Mask" "F.Paste")
			(net "GND")
		)
		(pad "AR46" smd circle
			(at 7.199884 -9.269984 180)
			(size 0.450088 0.450088)
			(layers "F.Cu" "F.Mask" "F.Paste")
			(net "PVDDCR_CPU0_P1")
		)
		(pad "AR47" smd circle
			(at 8.139938 -9.269984 180)
			(size 0.450088 0.450088)
			(layers "F.Cu" "F.Mask" "F.Paste")
			(net "GND")
		)
		(pad "AR48" smd circle
			(at 9.079992 -9.269984 180)
			(size 0.450088 0.450088)
			(layers "F.Cu" "F.Mask" "F.Paste")
			(net "PVDDCR_CPU0_P1")
		)
		(pad "AR49" smd circle
			(at 10.020046 -9.269984 180)
			(size 0.450088 0.450088)
			(layers "F.Cu" "F.Mask" "F.Paste")
			(net "GND")
		)
		(pad "AR50" smd circle
			(at 10.9601 -9.269984 180)
			(size 0.450088 0.450088)
			(layers "F.Cu" "F.Mask" "F.Paste")
			(net "PVDDCR_CPU0_P1")
		)
		(pad "AR51" smd circle
			(at 11.8999 -9.269984 180)
			(size 0.450088 0.450088)
			(layers "F.Cu" "F.Mask" "F.Paste")
			(net "GND")
		)
		(pad "AR52" smd circle
			(at 12.839954 -9.269984 180)
			(size 0.450088 0.450088)
			(layers "F.Cu" "F.Mask" "F.Paste")
			(net "PVDD18_S5_P1")
		)
		(pad "AR53" smd circle
			(at 13.780008 -9.269984 180)
			(size 0.450088 0.450088)
			(layers "F.Cu" "F.Mask" "F.Paste")
			(net "GND")
		)
		(pad "AR54" smd circle
			(at 14.720062 -9.269984 180)
			(size 0.450088 0.450088)
			(layers "F.Cu" "F.Mask" "F.Paste")
			(net "PVDD18_S5_P1")
		)
		(pad "AR55" smd circle
			(at 15.660116 -9.269984 180)
			(size 0.450088 0.450088)
			(layers "F.Cu" "F.Mask" "F.Paste")
			(net "M_C_CPU1_SA_CB<7>")
		)
		(pad "AR56" smd circle
			(at 16.599916 -9.269984 180)
			(size 0.450088 0.450088)
			(layers "F.Cu" "F.Mask" "F.Paste")
			(net "GND")
		)
		(pad "AR57" smd circle
			(at 17.53997 -9.269984 180)
			(size 0.450088 0.450088)
			(layers "F.Cu" "F.Mask" "F.Paste")
			(net "GND")
		)
		(pad "AR58" smd circle
			(at 18.480024 -9.269984 180)
			(size 0.450088 0.450088)
			(layers "F.Cu" "F.Mask" "F.Paste")
			(net "PVDDIO_P1")
		)
		(pad "AR59" smd circle
			(at 19.420078 -9.269984 180)
			(size 0.450088 0.450088)
			(layers "F.Cu" "F.Mask" "F.Paste")
			(net "M_D_CPU1_SA_CB<7>")
		)
		(pad "AR60" smd circle
			(at 20.359878 -9.269984 180)
			(size 0.450088 0.450088)
			(layers "F.Cu" "F.Mask" "F.Paste")
			(net "GND")
		)
		(pad "AR61" smd circle
			(at 21.299932 -9.269984 180)
			(size 0.450088 0.450088)
			(layers "F.Cu" "F.Mask" "F.Paste")
			(net "GND")
		)
		(pad "AR62" smd circle
			(at 22.239986 -9.269984 180)
			(size 0.450088 0.450088)
			(layers "F.Cu" "F.Mask" "F.Paste")
			(net "M_B_CPU1_SA_CB<7>")
		)
		(pad "AR63" smd circle
			(at 23.18004 -9.269984 180)
			(size 0.450088 0.450088)
			(layers "F.Cu" "F.Mask" "F.Paste")
			(net "GND")
		)
		(pad "AR64" smd circle
			(at 24.120094 -9.269984 180)
			(size 0.450088 0.450088)
			(layers "F.Cu" "F.Mask" "F.Paste")
			(net "GND")
		)
		(pad "AR65" smd circle
			(at 25.059894 -9.269984 180)
			(size 0.450088 0.450088)
			(layers "F.Cu" "F.Mask" "F.Paste")
			(net "PVDDIO_P1")
		)
		(pad "AR66" smd circle
			(at 25.999948 -9.269984 180)
			(size 0.450088 0.450088)
			(layers "F.Cu" "F.Mask" "F.Paste")
			(net "M_F_CPU1_SA_CB<7>")
		)
		(pad "AR67" smd circle
			(at 26.940002 -9.269984 180)
			(size 0.450088 0.450088)
			(layers "F.Cu" "F.Mask" "F.Paste")
			(net "GND")
		)
		(pad "AR68" smd circle
			(at 27.880056 -9.269984 180)
			(size 0.450088 0.450088)
			(layers "F.Cu" "F.Mask" "F.Paste")
			(net "GND")
		)
		(pad "AR69" smd circle
			(at 28.82011 -9.269984 180)
			(size 0.450088 0.450088)
			(layers "F.Cu" "F.Mask" "F.Paste")
			(net "M_E_CPU1_SA_CB<7>")
		)
		(pad "AR70" smd circle
			(at 29.75991 -9.269984 180)
			(size 0.450088 0.450088)
			(layers "F.Cu" "F.Mask" "F.Paste")
			(net "GND")
		)
		(pad "AR71" smd circle
			(at 30.699964 -9.269984 180)
			(size 0.450088 0.450088)
			(layers "F.Cu" "F.Mask" "F.Paste")
			(net "GND")
		)
		(pad "AR72" smd circle
			(at 31.640018 -9.269984 180)
			(size 0.450088 0.450088)
			(layers "F.Cu" "F.Mask" "F.Paste")
			(net "PVDDIO_P1")
		)
		(pad "AR73" smd circle
			(at 32.580072 -9.269984 180)
			(size 0.450088 0.450088)
			(layers "F.Cu" "F.Mask" "F.Paste")
			(net "M_A_CPU1_SA_CB<7>")
		)
		(pad "AR74" smd circle
			(at 33.519872 -9.269984 180)
			(size 0.450088 0.450088)
			(layers "F.Cu" "F.Mask" "F.Paste")
			(net "M_A_CPU1_ALERT_R_N")
		)
		(pad "AR75" smd circle
			(at 34.459926 -9.269984 180)
			(size 0.450088 0.450088)
			(layers "F.Cu" "F.Mask" "F.Paste")
			(net "GND")
		)
		(pad "AT2" smd circle
			(at -33.690052 -8.459978 180)
			(size 0.450088 0.450088)
			(layers "F.Cu" "F.Mask" "F.Paste")
			(net "M_G_CPU1_RESET_N")
		)
		(pad "AT3" smd circle
			(at -32.749998 -8.459978 180)
			(size 0.450088 0.450088)
			(layers "F.Cu" "F.Mask" "F.Paste")
			(net "GND")
		)
		(pad "AT4" smd circle
			(at -31.809944 -8.459978 180)
			(size 0.450088 0.450088)
			(layers "F.Cu" "F.Mask" "F.Paste")
			(net "GND")
		)
		(pad "AT5" smd circle
			(at -30.86989 -8.459978 180)
			(size 0.450088 0.450088)
			(layers "F.Cu" "F.Mask" "F.Paste")
			(net "GND")
		)
		(pad "AT6" smd circle
			(at -29.93009 -8.459978 180)
			(size 0.450088 0.450088)
			(layers "F.Cu" "F.Mask" "F.Paste")
			(net "GND")
		)
		(pad "AT7" smd circle
			(at -28.990036 -8.459978 180)
			(size 0.450088 0.450088)
			(layers "F.Cu" "F.Mask" "F.Paste")
			(net "M_K_CPU1_ALERT_R_N")
		)
		(pad "AT8" smd circle
			(at -28.049982 -8.459978 180)
			(size 0.450088 0.450088)
			(layers "F.Cu" "F.Mask" "F.Paste")
			(net "GND")
		)
		(pad "AT9" smd circle
			(at -27.109928 -8.459978 180)
			(size 0.450088 0.450088)
			(layers "F.Cu" "F.Mask" "F.Paste")
			(net "GND")
		)
		(pad "AT10" smd circle
			(at -26.170128 -8.459978 180)
			(size 0.450088 0.450088)
			(layers "F.Cu" "F.Mask" "F.Paste")
			(net "GND")
		)
		(pad "AT11" smd circle
			(at -25.230074 -8.459978 180)
			(size 0.450088 0.450088)
			(layers "F.Cu" "F.Mask" "F.Paste")
			(net "M_L_CPU1_ALERT_R_N")
		)
		(pad "AT12" smd circle
			(at -24.29002 -8.459978 180)
			(size 0.450088 0.450088)
			(layers "F.Cu" "F.Mask" "F.Paste")
			(net "GND")
		)
		(pad "AT13" smd circle
			(at -23.349966 -8.459978 180)
			(size 0.450088 0.450088)
			(layers "F.Cu" "F.Mask" "F.Paste")
			(net "GND")
		)
		(pad "AT14" smd circle
			(at -22.409912 -8.459978 180)
			(size 0.450088 0.450088)
			(layers "F.Cu" "F.Mask" "F.Paste")
			(net "M_H_CPU1_ALERT_R_N")
		)
		(pad "AT15" smd circle
			(at -21.470112 -8.459978 180)
			(size 0.450088 0.450088)
			(layers "F.Cu" "F.Mask" "F.Paste")
			(net "GND")
		)
		(pad "AT16" smd circle
			(at -20.530058 -8.459978 180)
			(size 0.450088 0.450088)
			(layers "F.Cu" "F.Mask" "F.Paste")
			(net "GND")
		)
		(pad "AT17" smd circle
			(at -19.590004 -8.459978 180)
			(size 0.450088 0.450088)
			(layers "F.Cu" "F.Mask" "F.Paste")
			(net "GND")
		)
		(pad "AT18" smd circle
			(at -18.64995 -8.459978 180)
			(size 0.450088 0.450088)
			(layers "F.Cu" "F.Mask" "F.Paste")
			(net "M_J_CPU1_ALERT_R_N")
		)
		(pad "AT19" smd circle
			(at -17.709896 -8.459978 180)
			(size 0.450088 0.450088)
			(layers "F.Cu" "F.Mask" "F.Paste")
			(net "GND")
		)
		(pad "AT20" smd circle
			(at -16.770096 -8.459978 180)
			(size 0.450088 0.450088)
			(layers "F.Cu" "F.Mask" "F.Paste")
			(net "GND")
		)
		(pad "AT21" smd circle
			(at -15.830042 -8.459978 180)
			(size 0.450088 0.450088)
			(layers "F.Cu" "F.Mask" "F.Paste")
			(net "M_I_CPU1_ALERT_R_N")
		)
		(pad "AT22" smd circle
			(at -14.889988 -8.459978 180)
			(size 0.450088 0.450088)
			(layers "F.Cu" "F.Mask" "F.Paste")
			(net "PVDDCR_SOC_P1")
		)
		(pad "AT23" smd circle
			(at -13.949934 -8.459978 180)
			(size 0.450088 0.450088)
			(layers "F.Cu" "F.Mask" "F.Paste")
			(net "GND")
		)
		(pad "AT24" smd circle
			(at -13.00988 -8.459978 180)
			(size 0.450088 0.450088)
			(layers "F.Cu" "F.Mask" "F.Paste")
			(net "PVDDCR_CPU0_P1")
		)
		(pad "AT25" smd circle
			(at -12.07008 -8.459978 180)
			(size 0.450088 0.450088)
			(layers "F.Cu" "F.Mask" "F.Paste")
			(net "GND")
		)
		(pad "AT26" smd circle
			(at -11.130026 -8.459978 180)
			(size 0.450088 0.450088)
			(layers "F.Cu" "F.Mask" "F.Paste")
			(net "PVDDCR_CPU0_P1")
		)
		(pad "AT27" smd circle
			(at -10.189972 -8.459978 180)
			(size 0.450088 0.450088)
			(layers "F.Cu" "F.Mask" "F.Paste")
			(net "GND")
		)
		(pad "AT28" smd circle
			(at -9.249918 -8.459978 180)
			(size 0.450088 0.450088)
			(layers "F.Cu" "F.Mask" "F.Paste")
			(net "PVDDCR_CPU0_P1")
		)
		(pad "AT29" smd circle
			(at -8.310118 -8.459978 180)
			(size 0.450088 0.450088)
			(layers "F.Cu" "F.Mask" "F.Paste")
			(net "GND")
		)
		(pad "AT30" smd circle
			(at -7.370064 -8.459978 180)
			(size 0.450088 0.450088)
			(layers "F.Cu" "F.Mask" "F.Paste")
			(net "PVDDCR_CPU0_P1")
		)
		(pad "AT31" smd circle
			(at -6.43001 -8.459978 180)
			(size 0.450088 0.450088)
			(layers "F.Cu" "F.Mask" "F.Paste")
			(net "GND")
		)
		(pad "AT32" smd circle
			(at -5.489956 -8.459978 180)
			(size 0.450088 0.450088)
			(layers "F.Cu" "F.Mask" "F.Paste")
			(net "PVDDCR_CPU0_P1")
		)
		(pad "AT33" smd circle
			(at -4.549902 -8.459978 180)
			(size 0.450088 0.450088)
			(layers "F.Cu" "F.Mask" "F.Paste")
			(net "GND")
		)
		(pad "AT34" smd circle
			(at -3.610102 -8.459978 180)
			(size 0.450088 0.450088)
			(layers "F.Cu" "F.Mask" "F.Paste")
			(net "PVDDCR_CPU0_P1")
		)
		(pad "AT35" smd circle
			(at -2.670048 -8.459978 180)
			(size 0.450088 0.450088)
			(layers "F.Cu" "F.Mask" "F.Paste")
			(net "GND")
		)
		(pad "AT36" smd circle
			(at -1.729994 -8.459978 180)
			(size 0.450088 0.450088)
			(layers "F.Cu" "F.Mask" "F.Paste")
			(net "PVDDCR_CPU0_P1")
		)
		(pad "AT37" smd circle
			(at -0.78994 -8.459978 180)
			(size 0.450088 0.450088)
			(layers "F.Cu" "F.Mask" "F.Paste")
			(net "GND")
		)
		(pad "AT39" smd circle
			(at 1.089914 -8.459978 180)
			(size 0.450088 0.450088)
			(layers "F.Cu" "F.Mask" "F.Paste")
			(net "PVDDCR_CPU0_P1")
		)
		(pad "AT40" smd circle
			(at 2.029968 -8.459978 180)
			(size 0.450088 0.450088)
			(layers "F.Cu" "F.Mask" "F.Paste")
			(net "GND")
		)
		(pad "AT41" smd circle
			(at 2.970022 -8.459978 180)
			(size 0.450088 0.450088)
			(layers "F.Cu" "F.Mask" "F.Paste")
			(net "PVDDCR_CPU0_P1")
		)
		(pad "AT42" smd circle
			(at 3.910076 -8.459978 180)
			(size 0.450088 0.450088)
			(layers "F.Cu" "F.Mask" "F.Paste")
			(net "GND")
		)
		(pad "AT43" smd circle
			(at 4.849876 -8.459978 180)
			(size 0.450088 0.450088)
			(layers "F.Cu" "F.Mask" "F.Paste")
			(net "PVDDCR_CPU0_P1")
		)
		(pad "AT44" smd circle
			(at 5.78993 -8.459978 180)
			(size 0.450088 0.450088)
			(layers "F.Cu" "F.Mask" "F.Paste")
			(net "GND")
		)
		(pad "AT45" smd circle
			(at 6.729984 -8.459978 180)
			(size 0.450088 0.450088)
			(layers "F.Cu" "F.Mask" "F.Paste")
			(net "PVDDCR_CPU0_P1")
		)
		(pad "AT46" smd circle
			(at 7.670038 -8.459978 180)
			(size 0.450088 0.450088)
			(layers "F.Cu" "F.Mask" "F.Paste")
			(net "GND")
		)
		(pad "AT47" smd circle
			(at 8.610092 -8.459978 180)
			(size 0.450088 0.450088)
			(layers "F.Cu" "F.Mask" "F.Paste")
			(net "PVDDCR_CPU0_P1")
		)
		(pad "AT48" smd circle
			(at 9.549892 -8.459978 180)
			(size 0.450088 0.450088)
			(layers "F.Cu" "F.Mask" "F.Paste")
			(net "GND")
		)
		(pad "AT49" smd circle
			(at 10.489946 -8.459978 180)
			(size 0.450088 0.450088)
			(layers "F.Cu" "F.Mask" "F.Paste")
			(net "PVDDCR_CPU0_P1")
		)
		(pad "AT50" smd circle
			(at 11.43 -8.459978 180)
			(size 0.450088 0.450088)
			(layers "F.Cu" "F.Mask" "F.Paste")
			(net "GND")
		)
		(pad "AT51" smd circle
			(at 12.370054 -8.459978 180)
			(size 0.450088 0.450088)
			(layers "F.Cu" "F.Mask" "F.Paste")
			(net "PVDD18_S5_P1")
		)
		(pad "AT52" smd circle
			(at 13.310108 -8.459978 180)
			(size 0.450088 0.450088)
			(layers "F.Cu" "F.Mask" "F.Paste")
			(net "GND")
		)
		(pad "AT53" smd circle
			(at 14.249908 -8.459978 180)
			(size 0.450088 0.450088)
			(layers "F.Cu" "F.Mask" "F.Paste")
			(net "PVDD18_S5_P1")
		)
		(pad "AT54" smd circle
			(at 15.189962 -8.459978 180)
			(size 0.450088 0.450088)
			(layers "F.Cu" "F.Mask" "F.Paste")
			(net "GND")
		)
		(pad "AT55" smd circle
			(at 16.130016 -8.459978 180)
			(size 0.450088 0.450088)
			(layers "F.Cu" "F.Mask" "F.Paste")
			(net "M_C_CPU1_ALERT_R_N")
		)
		(pad "AT56" smd circle
			(at 17.07007 -8.459978 180)
			(size 0.450088 0.450088)
			(layers "F.Cu" "F.Mask" "F.Paste")
			(net "GND")
		)
		(pad "AT57" smd circle
			(at 18.010124 -8.459978 180)
			(size 0.450088 0.450088)
			(layers "F.Cu" "F.Mask" "F.Paste")
			(net "GND")
		)
		(pad "AT58" smd circle
			(at 18.949924 -8.459978 180)
			(size 0.450088 0.450088)
			(layers "F.Cu" "F.Mask" "F.Paste")
			(net "M_D_CPU1_ALERT_R_N")
		)
		(pad "AT59" smd circle
			(at 19.889978 -8.459978 180)
			(size 0.450088 0.450088)
			(layers "F.Cu" "F.Mask" "F.Paste")
			(net "GND")
		)
	)
)
